(kicad_pcb
	(version 20260206)
	(generator "pcbnew")
	(generator_version "10.0")
	(general
		(thickness 1.6)
		(legacy_teardrops no)
	)
	(paper "A4")
	(title_block
		(title "Wiwynn_Tioga_Pass_MB.brd")
		(comment 1 "Tioga Pass / footprint 2018 of 4770 (J1G1), pads 1-123 of 291")
	)
	(layers
		(0 "F.Cu" signal "TOP")
		(4 "In1.Cu" signal "L2GND")
		(6 "In2.Cu" signal "L3")
		(8 "In3.Cu" signal "L4GND")
		(10 "In4.Cu" signal "L5")
		(12 "In5.Cu" signal "L6GND")
		(14 "In6.Cu" signal "L7VCC")
		(16 "In7.Cu" signal "L8VCC")
		(18 "In8.Cu" signal "L9GND")
		(20 "In9.Cu" signal "L10")
		(22 "In10.Cu" signal "L11GND")
		(24 "In11.Cu" signal "L12")
		(26 "In12.Cu" signal "L13GND")
		(2 "B.Cu" signal "BOTTOM")
		(9 "F.Adhes" user "F.Adhesive")
		(11 "B.Adhes" user "B.Adhesive")
		(13 "F.Paste" user "Package Geometry/Pastemask Top")
		(15 "B.Paste" user "Package Geometry/Pastemask Bottom")
		(5 "F.SilkS" user "Ref Des/Silkscreen Top")
		(7 "B.SilkS" user "Ref Des/Silkscreen Bottom")
		(1 "F.Mask" user "Board Geometry/Soldermask Top")
		(3 "B.Mask" user "Board Geometry/Soldermask Bottom")
		(17 "Dwgs.User" user "User.Drawings")
		(19 "Cmts.User" user "User.Comments")
		(21 "Eco1.User" user "User.Eco1")
		(23 "Eco2.User" user "User.Eco2")
		(25 "Edge.Cuts" user "Board Geometry/Outline")
		(27 "Margin" user)
		(31 "F.CrtYd" user "Package Geometry/Place Bound Top")
		(29 "B.CrtYd" user "Package Geometry/Place Bound Bottom")
		(35 "F.Fab" user "Ref Des/Assembly Top")
		(33 "B.Fab" user "Ref Des/Assembly Bottom")
	)
	(footprint ""
		(layer "F.Cu")
		(at 29.699458 -15.423642 90)
		(property "Reference" "J1G1"
			(at 9.314688 35.070542 0)
			(unlocked yes)
			(layer "F.SilkS")
			(effects
				(font
					(size 0.7874 0.5842)
					(thickness 0.1524)
				)
				(justify left)
			)
		)
		(property "Value" ""
			(at 0 0 90)
			(layer "F.Fab")
			(effects
				(font
					(size 1.27 1.27)
				)
			)
		)
		(duplicate_pad_numbers_are_jumpers no)
		(pad "" thru_hole circle
			(at 2.29997 -5.649976 90)
			(size 2.8194 2.8194)
			(drill 2.4384)
			(layers "*.Cu" "*.Mask")
			(remove_unused_layers no)
			(clearance 0.127)
			(thermal_gap 0.127)
		)
		(pad "" thru_hole oval
			(at 2.29997 68.90004 90)
			(size 2.8194 1.5748)
			(drill oval 2.4384 1.1938)
			(layers "*.Cu" "*.Mask")
			(remove_unused_layers no)
			(clearance 0.127)
			(thermal_gap 0.127)
		)
		(pad "" thru_hole circle
			(at 2.29997 132.299964 90)
			(size 2.8194 2.8194)
			(drill 2.4384)
			(layers "*.Cu" "*.Mask")
			(remove_unused_layers no)
			(clearance 0.127)
			(thermal_gap 0.127)
		)
		(pad "1" smd rect
			(at 0 0 90)
			(size 1.8034 0.508)
			(layers "F.Cu" "F.Mask" "F.Paste")
			(net "P12V_NVDIMM_GHJ")
		)
		(pad "2" smd rect
			(at 0 0.849884 90)
			(size 1.8034 0.508)
			(layers "F.Cu" "F.Mask" "F.Paste")
			(net "GND")
		)
		(pad "3" smd rect
			(at 0 1.700022 90)
			(size 1.8034 0.508)
			(layers "F.Cu" "F.Mask" "F.Paste")
			(net "M_G_DQ<5>")
		)
		(pad "4" smd rect
			(at 0 2.549906 90)
			(size 1.8034 0.508)
			(layers "F.Cu" "F.Mask" "F.Paste")
			(net "GND")
		)
		(pad "5" smd rect
			(at 0 3.400044 90)
			(size 1.8034 0.508)
			(layers "F.Cu" "F.Mask" "F.Paste")
			(net "M_G_DQ<1>")
		)
		(pad "6" smd rect
			(at 0 4.249928 90)
			(size 1.8034 0.508)
			(layers "F.Cu" "F.Mask" "F.Paste")
			(net "GND")
		)
		(pad "7" smd rect
			(at 0 5.100066 90)
			(size 1.8034 0.508)
			(layers "F.Cu" "F.Mask" "F.Paste")
			(net "M_G_DQS_DP<9>")
		)
		(pad "8" smd rect
			(at 0 5.94995 90)
			(size 1.8034 0.508)
			(layers "F.Cu" "F.Mask" "F.Paste")
			(net "M_G_DQS_DN<9>")
		)
		(pad "9" smd rect
			(at 0 6.800088 90)
			(size 1.8034 0.508)
			(layers "F.Cu" "F.Mask" "F.Paste")
			(net "GND")
		)
		(pad "10" smd rect
			(at 0 7.649972 90)
			(size 1.8034 0.508)
			(layers "F.Cu" "F.Mask" "F.Paste")
			(net "M_G_DQ<7>")
		)
		(pad "11" smd rect
			(at 0 8.50011 90)
			(size 1.8034 0.508)
			(layers "F.Cu" "F.Mask" "F.Paste")
			(net "GND")
		)
		(pad "12" smd rect
			(at 0 9.349994 90)
			(size 1.8034 0.508)
			(layers "F.Cu" "F.Mask" "F.Paste")
			(net "M_G_DQ<3>")
		)
		(pad "13" smd rect
			(at 0 10.199878 90)
			(size 1.8034 0.508)
			(layers "F.Cu" "F.Mask" "F.Paste")
			(net "GND")
		)
		(pad "14" smd rect
			(at 0 11.050016 90)
			(size 1.8034 0.508)
			(layers "F.Cu" "F.Mask" "F.Paste")
			(net "M_G_DQ<13>")
		)
		(pad "15" smd rect
			(at 0 11.8999 90)
			(size 1.8034 0.508)
			(layers "F.Cu" "F.Mask" "F.Paste")
			(net "GND")
		)
		(pad "16" smd rect
			(at 0 12.750038 90)
			(size 1.8034 0.508)
			(layers "F.Cu" "F.Mask" "F.Paste")
			(net "M_G_DQ<9>")
		)
		(pad "17" smd rect
			(at 0 13.599922 90)
			(size 1.8034 0.508)
			(layers "F.Cu" "F.Mask" "F.Paste")
			(net "GND")
		)
		(pad "18" smd rect
			(at 0 14.45006 90)
			(size 1.8034 0.508)
			(layers "F.Cu" "F.Mask" "F.Paste")
			(net "M_G_DQS_DP<10>")
		)
		(pad "19" smd rect
			(at 0 15.299944 90)
			(size 1.8034 0.508)
			(layers "F.Cu" "F.Mask" "F.Paste")
			(net "M_G_DQS_DN<10>")
		)
		(pad "20" smd rect
			(at 0 16.150082 90)
			(size 1.8034 0.508)
			(layers "F.Cu" "F.Mask" "F.Paste")
			(net "GND")
		)
		(pad "21" smd rect
			(at 0 16.999966 90)
			(size 1.8034 0.508)
			(layers "F.Cu" "F.Mask" "F.Paste")
			(net "M_G_DQ<15>")
		)
		(pad "22" smd rect
			(at 0 17.850104 90)
			(size 1.8034 0.508)
			(layers "F.Cu" "F.Mask" "F.Paste")
			(net "GND")
		)
		(pad "23" smd rect
			(at 0 18.699988 90)
			(size 1.8034 0.508)
			(layers "F.Cu" "F.Mask" "F.Paste")
			(net "M_G_DQ<11>")
		)
		(pad "24" smd rect
			(at 0 19.550126 90)
			(size 1.8034 0.508)
			(layers "F.Cu" "F.Mask" "F.Paste")
			(net "GND")
		)
		(pad "25" smd rect
			(at 0 20.40001 90)
			(size 1.8034 0.508)
			(layers "F.Cu" "F.Mask" "F.Paste")
			(net "M_G_DQ<21>")
		)
		(pad "26" smd rect
			(at 0 21.249894 90)
			(size 1.8034 0.508)
			(layers "F.Cu" "F.Mask" "F.Paste")
			(net "GND")
		)
		(pad "27" smd rect
			(at 0 22.100032 90)
			(size 1.8034 0.508)
			(layers "F.Cu" "F.Mask" "F.Paste")
			(net "M_G_DQ<17>")
		)
		(pad "28" smd rect
			(at 0 22.949916 90)
			(size 1.8034 0.508)
			(layers "F.Cu" "F.Mask" "F.Paste")
			(net "GND")
		)
		(pad "29" smd rect
			(at 0 23.800054 90)
			(size 1.8034 0.508)
			(layers "F.Cu" "F.Mask" "F.Paste")
			(net "M_G_DQS_DP<11>")
		)
		(pad "30" smd rect
			(at 0 24.649938 90)
			(size 1.8034 0.508)
			(layers "F.Cu" "F.Mask" "F.Paste")
			(net "M_G_DQS_DN<11>")
		)
		(pad "31" smd rect
			(at 0 25.500076 90)
			(size 1.8034 0.508)
			(layers "F.Cu" "F.Mask" "F.Paste")
			(net "GND")
		)
		(pad "32" smd rect
			(at 0 26.34996 90)
			(size 1.8034 0.508)
			(layers "F.Cu" "F.Mask" "F.Paste")
			(net "M_G_DQ<23>")
		)
		(pad "33" smd rect
			(at 0 27.200098 90)
			(size 1.8034 0.508)
			(layers "F.Cu" "F.Mask" "F.Paste")
			(net "GND")
		)
		(pad "34" smd rect
			(at 0 28.049982 90)
			(size 1.8034 0.508)
			(layers "F.Cu" "F.Mask" "F.Paste")
			(net "M_G_DQ<19>")
		)
		(pad "35" smd rect
			(at 0 28.90012 90)
			(size 1.8034 0.508)
			(layers "F.Cu" "F.Mask" "F.Paste")
			(net "GND")
		)
		(pad "36" smd rect
			(at 0 29.750004 90)
			(size 1.8034 0.508)
			(layers "F.Cu" "F.Mask" "F.Paste")
			(net "M_G_DQ<29>")
		)
		(pad "37" smd rect
			(at 0 30.599888 90)
			(size 1.8034 0.508)
			(layers "F.Cu" "F.Mask" "F.Paste")
			(net "GND")
		)
		(pad "38" smd rect
			(at 0 31.450026 90)
			(size 1.8034 0.508)
			(layers "F.Cu" "F.Mask" "F.Paste")
			(net "M_G_DQ<25>")
		)
		(pad "39" smd rect
			(at 0 32.29991 90)
			(size 1.8034 0.508)
			(layers "F.Cu" "F.Mask" "F.Paste")
			(net "GND")
		)
		(pad "40" smd rect
			(at 0 33.150048 90)
			(size 1.8034 0.508)
			(layers "F.Cu" "F.Mask" "F.Paste")
			(net "M_G_DQS_DP<12>")
		)
		(pad "41" smd rect
			(at 0 33.999932 90)
			(size 1.8034 0.508)
			(layers "F.Cu" "F.Mask" "F.Paste")
			(net "M_G_DQS_DN<12>")
		)
		(pad "42" smd rect
			(at 0 34.85007 90)
			(size 1.8034 0.508)
			(layers "F.Cu" "F.Mask" "F.Paste")
			(net "GND")
		)
		(pad "43" smd rect
			(at 0 35.699954 90)
			(size 1.8034 0.508)
			(layers "F.Cu" "F.Mask" "F.Paste")
			(net "M_G_DQ<31>")
		)
		(pad "44" smd rect
			(at 0 36.550092 90)
			(size 1.8034 0.508)
			(layers "F.Cu" "F.Mask" "F.Paste")
			(net "GND")
		)
		(pad "45" smd rect
			(at 0 37.399976 90)
			(size 1.8034 0.508)
			(layers "F.Cu" "F.Mask" "F.Paste")
			(net "M_G_DQ<27>")
		)
		(pad "46" smd rect
			(at 0 38.250114 90)
			(size 1.8034 0.508)
			(layers "F.Cu" "F.Mask" "F.Paste")
			(net "GND")
		)
		(pad "47" smd rect
			(at 0 39.099998 90)
			(size 1.8034 0.508)
			(layers "F.Cu" "F.Mask" "F.Paste")
			(net "M_G_ECC<5>")
		)
		(pad "48" smd rect
			(at 0 39.949882 90)
			(size 1.8034 0.508)
			(layers "F.Cu" "F.Mask" "F.Paste")
			(net "GND")
		)
		(pad "49" smd rect
			(at 0 40.80002 90)
			(size 1.8034 0.508)
			(layers "F.Cu" "F.Mask" "F.Paste")
			(net "M_G_ECC<1>")
		)
		(pad "50" smd rect
			(at 0 41.649904 90)
			(size 1.8034 0.508)
			(layers "F.Cu" "F.Mask" "F.Paste")
			(net "GND")
		)
		(pad "51" smd rect
			(at 0 42.500042 90)
			(size 1.8034 0.508)
			(layers "F.Cu" "F.Mask" "F.Paste")
			(net "M_G_DQS_DP<17>")
		)
		(pad "52" smd rect
			(at 0 43.349926 90)
			(size 1.8034 0.508)
			(layers "F.Cu" "F.Mask" "F.Paste")
			(net "M_G_DQS_DN<17>")
		)
		(pad "53" smd rect
			(at 0 44.200064 90)
			(size 1.8034 0.508)
			(layers "F.Cu" "F.Mask" "F.Paste")
			(net "GND")
		)
		(pad "54" smd rect
			(at 0 45.049948 90)
			(size 1.8034 0.508)
			(layers "F.Cu" "F.Mask" "F.Paste")
			(net "M_G_ECC<7>")
		)
		(pad "55" smd rect
			(at 0 45.900086 90)
			(size 1.8034 0.508)
			(layers "F.Cu" "F.Mask" "F.Paste")
			(net "GND")
		)
		(pad "56" smd rect
			(at 0 46.74997 90)
			(size 1.8034 0.508)
			(layers "F.Cu" "F.Mask" "F.Paste")
			(net "M_G_ECC<3>")
		)
		(pad "57" smd rect
			(at 0 47.600108 90)
			(size 1.8034 0.508)
			(layers "F.Cu" "F.Mask" "F.Paste")
			(net "GND")
		)
		(pad "58" smd rect
			(at 0 48.449992 90)
			(size 1.8034 0.508)
			(layers "F.Cu" "F.Mask" "F.Paste")
			(net "M_GHJ_RST_N")
		)
		(pad "59" smd rect
			(at 0 49.299876 90)
			(size 1.8034 0.508)
			(layers "F.Cu" "F.Mask" "F.Paste")
			(net "PVDDQ_GHJ")
		)
		(pad "60" smd rect
			(at 0 50.150014 90)
			(size 1.8034 0.508)
			(layers "F.Cu" "F.Mask" "F.Paste")
			(net "M_G_CKE<0>")
		)
		(pad "61" smd rect
			(at 0 50.999898 90)
			(size 1.8034 0.508)
			(layers "F.Cu" "F.Mask" "F.Paste")
			(net "PVDDQ_GHJ")
		)
		(pad "62" smd rect
			(at 0 51.850036 90)
			(size 1.8034 0.508)
			(layers "F.Cu" "F.Mask" "F.Paste")
			(net "M_G_ACT_N")
		)
		(pad "63" smd rect
			(at 0 52.69992 90)
			(size 1.8034 0.508)
			(layers "F.Cu" "F.Mask" "F.Paste")
			(net "M_G_BG<0>")
		)
		(pad "64" smd rect
			(at 0 53.550058 90)
			(size 1.8034 0.508)
			(layers "F.Cu" "F.Mask" "F.Paste")
			(net "PVDDQ_GHJ")
		)
		(pad "65" smd rect
			(at 0 54.399942 90)
			(size 1.8034 0.508)
			(layers "F.Cu" "F.Mask" "F.Paste")
			(net "M_G_MA<12>")
		)
		(pad "66" smd rect
			(at 0 55.25008 90)
			(size 1.8034 0.508)
			(layers "F.Cu" "F.Mask" "F.Paste")
			(net "M_G_MA<9>")
		)
		(pad "67" smd rect
			(at 0 56.099964 90)
			(size 1.8034 0.508)
			(layers "F.Cu" "F.Mask" "F.Paste")
			(net "PVDDQ_GHJ")
		)
		(pad "68" smd rect
			(at 0 56.950102 90)
			(size 1.8034 0.508)
			(layers "F.Cu" "F.Mask" "F.Paste")
			(net "M_G_MA<8>")
		)
		(pad "69" smd rect
			(at 0 57.799986 90)
			(size 1.8034 0.508)
			(layers "F.Cu" "F.Mask" "F.Paste")
			(net "M_G_MA<6>")
		)
		(pad "70" smd rect
			(at 0 58.650124 90)
			(size 1.8034 0.508)
			(layers "F.Cu" "F.Mask" "F.Paste")
			(net "PVDDQ_GHJ")
		)
		(pad "71" smd rect
			(at 0 59.500008 90)
			(size 1.8034 0.508)
			(layers "F.Cu" "F.Mask" "F.Paste")
			(net "M_G_MA<3>")
		)
		(pad "72" smd rect
			(at 0 60.349892 90)
			(size 1.8034 0.508)
			(layers "F.Cu" "F.Mask" "F.Paste")
			(net "M_G_MA<1>")
		)
		(pad "73" smd rect
			(at 0 61.20003 90)
			(size 1.8034 0.508)
			(layers "F.Cu" "F.Mask" "F.Paste")
			(net "PVDDQ_GHJ")
		)
		(pad "74" smd rect
			(at 0 62.049914 90)
			(size 1.8034 0.508)
			(layers "F.Cu" "F.Mask" "F.Paste")
			(net "M_G_CLK_DP<0>")
		)
		(pad "75" smd rect
			(at 0 62.900052 90)
			(size 1.8034 0.508)
			(layers "F.Cu" "F.Mask" "F.Paste")
			(net "M_G_CLK_DN<0>")
		)
		(pad "76" smd rect
			(at 0 63.749936 90)
			(size 1.8034 0.508)
			(layers "F.Cu" "F.Mask" "F.Paste")
			(net "PVDDQ_GHJ")
		)
		(pad "77" smd rect
			(at 0 64.600074 90)
			(size 1.8034 0.508)
			(layers "F.Cu" "F.Mask" "F.Paste")
			(net "PVTT_GHJ")
		)
		(pad "78" smd rect
			(at 0 70.550024 90)
			(size 1.8034 0.508)
			(layers "F.Cu" "F.Mask" "F.Paste")
			(net "FM_DIMM_EVENT_COD_N")
		)
		(pad "79" smd rect
			(at 0 71.399908 90)
			(size 1.8034 0.508)
			(layers "F.Cu" "F.Mask" "F.Paste")
			(net "M_G_MA<0>")
		)
		(pad "80" smd rect
			(at 0 72.250046 90)
			(size 1.8034 0.508)
			(layers "F.Cu" "F.Mask" "F.Paste")
			(net "PVDDQ_GHJ")
		)
		(pad "81" smd rect
			(at 0 73.09993 90)
			(size 1.8034 0.508)
			(layers "F.Cu" "F.Mask" "F.Paste")
			(net "M_G_BA<0>")
		)
		(pad "82" smd rect
			(at 0 73.950068 90)
			(size 1.8034 0.508)
			(layers "F.Cu" "F.Mask" "F.Paste")
			(net "M_G_MA<16>")
		)
		(pad "83" smd rect
			(at 0 74.799952 90)
			(size 1.8034 0.508)
			(layers "F.Cu" "F.Mask" "F.Paste")
			(net "PVDDQ_GHJ")
		)
		(pad "84" smd rect
			(at 0 75.65009 90)
			(size 1.8034 0.508)
			(layers "F.Cu" "F.Mask" "F.Paste")
			(net "M_G_CS_N<0>")
		)
		(pad "85" smd rect
			(at 0 76.499974 90)
			(size 1.8034 0.508)
			(layers "F.Cu" "F.Mask" "F.Paste")
			(net "PVDDQ_GHJ")
		)
		(pad "86" smd rect
			(at 0 77.350112 90)
			(size 1.8034 0.508)
			(layers "F.Cu" "F.Mask" "F.Paste")
			(net "M_G_MA<15>")
		)
		(pad "87" smd rect
			(at 0 78.199996 90)
			(size 1.8034 0.508)
			(layers "F.Cu" "F.Mask" "F.Paste")
			(net "M_G_ODT<0>")
		)
		(pad "88" smd rect
			(at 0 79.04988 90)
			(size 1.8034 0.508)
			(layers "F.Cu" "F.Mask" "F.Paste")
			(net "PVDDQ_GHJ")
		)
		(pad "89" smd rect
			(at 0 79.900018 90)
			(size 1.8034 0.508)
			(layers "F.Cu" "F.Mask" "F.Paste")
			(net "M_G_CS_N<1>")
		)
		(pad "90" smd rect
			(at 0 80.749902 90)
			(size 1.8034 0.508)
			(layers "F.Cu" "F.Mask" "F.Paste")
			(net "PVDDQ_GHJ")
		)
		(pad "91" smd rect
			(at 0 81.60004 90)
			(size 1.8034 0.508)
			(layers "F.Cu" "F.Mask" "F.Paste")
			(net "M_G_ODT<1>")
		)
		(pad "92" smd rect
			(at 0 82.449924 90)
			(size 1.8034 0.508)
			(layers "F.Cu" "F.Mask" "F.Paste")
			(net "PVDDQ_GHJ")
		)
		(pad "93" smd rect
			(at 0 83.300062 90)
			(size 1.8034 0.508)
			(layers "F.Cu" "F.Mask" "F.Paste")
			(net "M_G_CS_N<2>")
		)
		(pad "94" smd rect
			(at 0 84.149946 90)
			(size 1.8034 0.508)
			(layers "F.Cu" "F.Mask" "F.Paste")
			(net "GND")
		)
		(pad "95" smd rect
			(at 0 85.000084 90)
			(size 1.8034 0.508)
			(layers "F.Cu" "F.Mask" "F.Paste")
			(net "M_G_DQ<37>")
		)
		(pad "96" smd rect
			(at 0 85.849968 90)
			(size 1.8034 0.508)
			(layers "F.Cu" "F.Mask" "F.Paste")
			(net "GND")
		)
		(pad "97" smd rect
			(at 0 86.700106 90)
			(size 1.8034 0.508)
			(layers "F.Cu" "F.Mask" "F.Paste")
			(net "M_G_DQ<33>")
		)
		(pad "98" smd rect
			(at 0 87.54999 90)
			(size 1.8034 0.508)
			(layers "F.Cu" "F.Mask" "F.Paste")
			(net "GND")
		)
		(pad "99" smd rect
			(at 0 88.399874 90)
			(size 1.8034 0.508)
			(layers "F.Cu" "F.Mask" "F.Paste")
			(net "M_G_DQS_DP<13>")
		)
		(pad "100" smd rect
			(at 0 89.250012 90)
			(size 1.8034 0.508)
			(layers "F.Cu" "F.Mask" "F.Paste")
			(net "M_G_DQS_DN<13>")
		)
		(pad "101" smd rect
			(at 0 90.099896 90)
			(size 1.8034 0.508)
			(layers "F.Cu" "F.Mask" "F.Paste")
			(net "GND")
		)
		(pad "102" smd rect
			(at 0 90.950034 90)
			(size 1.8034 0.508)
			(layers "F.Cu" "F.Mask" "F.Paste")
			(net "M_G_DQ<39>")
		)
		(pad "103" smd rect
			(at 0 91.799918 90)
			(size 1.8034 0.508)
			(layers "F.Cu" "F.Mask" "F.Paste")
			(net "GND")
		)
		(pad "104" smd rect
			(at 0 92.650056 90)
			(size 1.8034 0.508)
			(layers "F.Cu" "F.Mask" "F.Paste")
			(net "M_G_DQ<35>")
		)
		(pad "105" smd rect
			(at 0 93.49994 90)
			(size 1.8034 0.508)
			(layers "F.Cu" "F.Mask" "F.Paste")
			(net "GND")
		)
		(pad "106" smd rect
			(at 0 94.350078 90)
			(size 1.8034 0.508)
			(layers "F.Cu" "F.Mask" "F.Paste")
			(net "M_G_DQ<45>")
		)
		(pad "107" smd rect
			(at 0 95.199962 90)
			(size 1.8034 0.508)
			(layers "F.Cu" "F.Mask" "F.Paste")
			(net "GND")
		)
		(pad "108" smd rect
			(at 0 96.0501 90)
			(size 1.8034 0.508)
			(layers "F.Cu" "F.Mask" "F.Paste")
			(net "M_G_DQ<41>")
		)
		(pad "109" smd rect
			(at 0 96.899984 90)
			(size 1.8034 0.508)
			(layers "F.Cu" "F.Mask" "F.Paste")
			(net "GND")
		)
		(pad "110" smd rect
			(at 0 97.750122 90)
			(size 1.8034 0.508)
			(layers "F.Cu" "F.Mask" "F.Paste")
			(net "M_G_DQS_DP<14>")
		)
		(pad "111" smd rect
			(at 0 98.600006 90)
			(size 1.8034 0.508)
			(layers "F.Cu" "F.Mask" "F.Paste")
			(net "M_G_DQS_DN<14>")
		)
		(pad "112" smd rect
			(at 0 99.44989 90)
			(size 1.8034 0.508)
			(layers "F.Cu" "F.Mask" "F.Paste")
			(net "GND")
		)
		(pad "113" smd rect
			(at 0 100.300028 90)
			(size 1.8034 0.508)
			(layers "F.Cu" "F.Mask" "F.Paste")
			(net "M_G_DQ<47>")
		)
		(pad "114" smd rect
			(at 0 101.149912 90)
			(size 1.8034 0.508)
			(layers "F.Cu" "F.Mask" "F.Paste")
			(net "GND")
		)
		(pad "115" smd rect
			(at 0 102.00005 90)
			(size 1.8034 0.508)
			(layers "F.Cu" "F.Mask" "F.Paste")
			(net "M_G_DQ<43>")
		)
		(pad "116" smd rect
			(at 0 102.849934 90)
			(size 1.8034 0.508)
			(layers "F.Cu" "F.Mask" "F.Paste")
			(net "GND")
		)
		(pad "117" smd rect
			(at 0 103.700072 90)
			(size 1.8034 0.508)
			(layers "F.Cu" "F.Mask" "F.Paste")
			(net "M_G_DQ<53>")
		)
		(pad "118" smd rect
			(at 0 104.549956 90)
			(size 1.8034 0.508)
			(layers "F.Cu" "F.Mask" "F.Paste")
			(net "GND")
		)
		(pad "119" smd rect
			(at 0 105.400094 90)
			(size 1.8034 0.508)
			(layers "F.Cu" "F.Mask" "F.Paste")
			(net "M_G_DQ<49>")
		)
		(pad "120" smd rect
			(at 0 106.249978 90)
			(size 1.8034 0.508)
			(layers "F.Cu" "F.Mask" "F.Paste")
			(net "GND")
		)
	)
)
